(kicad_pcb
	(version 20260206)
	(generator "pcbnew")
	(generator_version "10.0")
	(general
		(thickness 1.6)
		(legacy_teardrops no)
	)
	(paper "A4")
	(title_block
		(title "01162023_DA0F0TEBIF0_F0T_Expander_BD_F_brd_V02_OCP.brd")
		(comment 1 "Grand Teton / footprints 2130-2135 of 9728")
	)
	(layers
		(0 "F.Cu" signal "TOP")
		(4 "In1.Cu" signal "GND")
		(6 "In2.Cu" signal "VCC")
		(8 "In3.Cu" signal "VCC1")
		(10 "In4.Cu" signal "GND1")
		(12 "In5.Cu" signal "IN1")
		(14 "In6.Cu" signal "GND2")
		(16 "In7.Cu" signal "IN2")
		(18 "In8.Cu" signal "GND3")
		(20 "In9.Cu" signal "IN3")
		(22 "In10.Cu" signal "GND4")
		(24 "In11.Cu" signal "IN4")
		(26 "In12.Cu" signal "GND5")
		(28 "In13.Cu" signal "IN5")
		(30 "In14.Cu" signal "GND6")
		(32 "In15.Cu" signal "IN6")
		(34 "In16.Cu" signal "GND7")
		(2 "B.Cu" signal "BOTTOM")
		(9 "F.Adhes" user "F.Adhesive")
		(11 "B.Adhes" user "B.Adhesive")
		(13 "F.Paste" user "Package Geometry/Pastemask Top")
		(15 "B.Paste" user "Package Geometry/Pastemask Bottom")
		(5 "F.SilkS" user "Ref Des/Silkscreen Top")
		(7 "B.SilkS" user "Ref Des/Silkscreen Bottom")
		(1 "F.Mask" user "Board Geometry/Soldermask Top")
		(3 "B.Mask" user "Board Geometry/Soldermask Bottom")
		(17 "Dwgs.User" user "User.Drawings")
		(19 "Cmts.User" user "User.Comments")
		(21 "Eco1.User" user "User.Eco1")
		(23 "Eco2.User" user "User.Eco2")
		(25 "Edge.Cuts" user "Board Geometry/Outline")
		(27 "Margin" user)
		(31 "F.CrtYd" user "Package Geometry/Place Bound Top")
		(29 "B.CrtYd" user "Package Geometry/Place Bound Bottom")
		(35 "F.Fab" user "Ref Des/Assembly Top")
		(33 "B.Fab" user "Ref Des/Assembly Bottom")
	)
	(footprint ""
		(layer "F.Cu")
		(at 425.911518 -71.458074 -90)
		(property "Reference" "PD37"
			(at 4.351274 -2.790952 90)
			(unlocked yes)
			(layer "F.SilkS")
			(effects
				(font
					(size 0.7874 0.5842)
					(thickness 0.1524)
				)
				(justify left)
			)
		)
		(property "Value" ""
			(at 0 0 270)
			(layer "F.Fab")
			(effects
				(font
					(size 1.27 1.27)
				)
			)
		)
		(duplicate_pad_numbers_are_jumpers no)
		(fp_line
			(start -3.656584 1.970024)
			(end 4.240784 1.970024)
			(stroke
				(width 0.1524)
				(type default)
			)
			(layer "F.SilkS")
		)
		(fp_line
			(start 4.240784 1.970024)
			(end 4.240784 -1.970024)
			(stroke
				(width 0.1524)
				(type default)
			)
			(layer "F.SilkS")
		)
		(fp_line
			(start -3.656584 -1.970024)
			(end -3.656584 1.970024)
			(stroke
				(width 0.1524)
				(type default)
			)
			(layer "F.SilkS")
		)
		(fp_line
			(start 4.240784 -1.970024)
			(end -3.656584 -1.970024)
			(stroke
				(width 0.1524)
				(type default)
			)
			(layer "F.SilkS")
		)
		(fp_poly
			(pts
				(xy 3.580384 1.970024) (xy 3.580384 -1.970024) (xy 4.240784 -1.970024) (xy 4.240784 1.970024)
			)
			(stroke
				(width 0)
				(type default)
			)
			(fill yes)
			(layer "F.SilkS")
		)
		(fp_line
			(start -2.3749 1.970024)
			(end 2.3749 1.970024)
			(stroke
				(width 0.1)
				(type default)
			)
			(layer "F.Fab")
		)
		(fp_line
			(start 2.3749 1.970024)
			(end 2.3749 -1.970024)
			(stroke
				(width 0.1)
				(type default)
			)
			(layer "F.Fab")
		)
		(fp_line
			(start -2.3749 -1.970024)
			(end -2.3749 1.970024)
			(stroke
				(width 0.1)
				(type default)
			)
			(layer "F.Fab")
		)
		(fp_line
			(start 2.3749 -1.970024)
			(end -2.3749 -1.970024)
			(stroke
				(width 0.1)
				(type default)
			)
			(layer "F.Fab")
		)
		(fp_text user "+"
			(at -4.9784 -0.23495 270)
			(unlocked yes)
			(layer "F.Fab")
			(effects
				(font
					(size 1.905 1.4224)
					(thickness 0.1524)
				)
				(justify left)
			)
		)
		(fp_text user "-"
			(at 4.1656 -0.23495 270)
			(unlocked yes)
			(layer "F.Fab")
			(effects
				(font
					(size 1.905 1.4224)
					(thickness 0.1524)
				)
				(justify left)
			)
		)
		(pad "A" smd rect
			(at -2.450084 0 270)
			(size 2.159 2.2606)
			(layers "F.Cu" "F.Mask" "F.Paste")
			(net "GND")
		)
		(pad "C" smd rect
			(at 2.450084 0 270)
			(size 2.159 2.2606)
			(layers "F.Cu" "F.Mask" "F.Paste")
			(net "P12V_AUX")
		)
	)
	(footprint ""
		(layer "F.Cu")
		(at 6.89102 -55.663846 90)
		(property "Reference" "PU54"
			(at -1.230376 2.791968 90)
			(unlocked yes)
			(layer "F.SilkS")
			(effects
				(font
					(size 0.7874 0.5842)
					(thickness 0.1524)
				)
				(justify left)
			)
		)
		(property "Value" ""
			(at 0 0 90)
			(layer "F.Fab")
			(effects
				(font
					(size 1.27 1.27)
				)
			)
		)
		(duplicate_pad_numbers_are_jumpers no)
		(fp_line
			(start 1.943608 -1.549908)
			(end 1.943608 1.549908)
			(stroke
				(width 0.1524)
				(type default)
			)
			(layer "F.SilkS")
		)
		(fp_line
			(start -1.943608 -1.549908)
			(end 1.943608 -1.549908)
			(stroke
				(width 0.1524)
				(type default)
			)
			(layer "F.SilkS")
		)
		(fp_line
			(start 1.943608 1.549908)
			(end -1.943608 1.549908)
			(stroke
				(width 0.1524)
				(type default)
			)
			(layer "F.SilkS")
		)
		(fp_line
			(start -1.943608 1.549908)
			(end -1.943608 -1.549908)
			(stroke
				(width 0.1524)
				(type default)
			)
			(layer "F.SilkS")
		)
		(fp_poly
			(pts
				(xy -2.019808 -1.549908) (xy -1.257808 -1.549908) (xy -1.257808 -1.880108) (xy -2.019808 -1.880108)
			)
			(stroke
				(width 0)
				(type default)
			)
			(fill yes)
			(layer "F.SilkS")
		)
		(fp_line
			(start 1.549908 -1.549908)
			(end 1.549908 1.549908)
			(stroke
				(width 0.1)
				(type default)
			)
			(layer "F.Fab")
		)
		(fp_line
			(start -1.549908 -1.549908)
			(end 1.549908 -1.549908)
			(stroke
				(width 0.1)
				(type default)
			)
			(layer "F.Fab")
		)
		(fp_line
			(start 1.549908 1.549908)
			(end -1.549908 1.549908)
			(stroke
				(width 0.1)
				(type default)
			)
			(layer "F.Fab")
		)
		(fp_line
			(start -1.549908 1.549908)
			(end -1.549908 -1.549908)
			(stroke
				(width 0.1)
				(type default)
			)
			(layer "F.Fab")
		)
		(fp_poly
			(pts
				(xy -2.019808 -1.549908) (xy -1.257808 -1.549908) (xy -1.257808 -1.880108) (xy -2.019808 -1.880108)
			)
			(stroke
				(width 0)
				(type default)
			)
			(fill yes)
			(layer "F.Fab")
		)
		(pad "1" smd rect
			(at -1.500124 -1.249934)
			(size 0.2794 0.6096)
			(layers "F.Cu" "F.Mask" "F.Paste")
			(net "P3V3_SSD0")
		)
		(pad "2" smd rect
			(at -1.500124 -0.750062)
			(size 0.2794 0.6096)
			(layers "F.Cu" "F.Mask" "F.Paste")
			(net "P3V3_SSD0")
		)
		(pad "3" smd rect
			(at -1.500124 -0.249936)
			(size 0.2794 0.6096)
			(layers "F.Cu" "F.Mask" "F.Paste")
			(net "P3V3_SSD0")
		)
		(pad "4" smd rect
			(at -1.500124 0.249936)
			(size 0.2794 0.6096)
			(layers "F.Cu" "F.Mask" "F.Paste")
			(net "P3V3_SSD0")
		)
		(pad "5" smd rect
			(at -1.500124 0.750062)
			(size 0.2794 0.6096)
			(layers "F.Cu" "F.Mask" "F.Paste")
			(net "P3V3_SSD0")
		)
		(pad "6" smd rect
			(at -1.500124 1.249934)
			(size 0.2794 0.6096)
			(layers "F.Cu" "F.Mask" "F.Paste")
			(net "GND")
		)
		(pad "7" smd rect
			(at 1.500124 1.249934)
			(size 0.2794 0.6096)
			(layers "F.Cu" "F.Mask" "F.Paste")
			(net "P3V3_SSD0_SS")
		)
		(pad "8" smd rect
			(at 1.500124 0.750062)
			(size 0.2794 0.6096)
			(layers "F.Cu" "F.Mask" "F.Paste")
			(net "PWRGD_P3V3_SSD0")
		)
		(pad "9" smd rect
			(at 1.500124 0.249936)
			(size 0.2794 0.6096)
			(layers "F.Cu" "F.Mask" "F.Paste")
			(net "P3V3_SSD0_OCP")
		)
		(pad "10" smd rect
			(at 1.500124 -0.249936)
			(size 0.2794 0.6096)
			(layers "F.Cu" "F.Mask" "F.Paste")
			(net "P5V_AUX")
		)
		(pad "11" smd rect
			(at 1.500124 -0.750062)
			(size 0.2794 0.6096)
			(layers "F.Cu" "F.Mask" "F.Paste")
			(net "SSD0_AUX_P3V3_EN_R")
		)
		(pad "12" smd rect
			(at 1.500124 -1.249934)
			(size 0.2794 0.6096)
			(layers "F.Cu" "F.Mask" "F.Paste")
			(net "P3V3_AUX")
		)
		(pad "13" smd rect
			(at 0 0 90)
			(size 1.9812 2.7178)
			(layers "F.Cu" "F.Mask" "F.Paste")
			(net "P3V3_AUX")
		)
		(zone
			(layer "F.Cu")
			(hatch none 0.5)
			(connect_pads
				(clearance 0)
			)
			(min_thickness 0.25)
			(keepout
				(tracks not_allowed)
				(vias allowed)
				(pads allowed)
				(copperpour not_allowed)
				(footprints allowed)
			)
			(placement
				(enabled no)
				(sheetname "")
			)
			(fill
				(thermal_gap 0.5)
				(thermal_bridge_width 0.5)
				(island_removal_mode 0)
			)
			(polygon
				(pts
					(xy 5.34162 -56.806846) (xy 5.46862 -56.806846) (xy 8.44042 -56.806846) (xy 8.440928 -56.806846)
					(xy 8.440928 -54.520846) (xy 8.44042 -54.520846) (xy 8.31342 -54.520846) (xy 6.89102 -54.520846)
					(xy 6.89102 -54.622446) (xy 8.31342 -54.622446) (xy 8.31342 -56.705246) (xy 5.46862 -56.705246)
					(xy 5.46862 -54.622446) (xy 6.86562 -54.622446) (xy 6.86562 -54.520846) (xy 5.46862 -54.520846)
					(xy 5.34162 -54.520846) (xy 5.341112 -54.520846) (xy 5.341112 -56.806846)
				)
			)
		)
	)
	(footprint ""
		(layer "F.Cu")
		(at 189.047374 -21.37156)
		(property "Reference" "C3918"
			(at 0 0 0)
			(layer "F.SilkS")
			(hide yes)
			(effects
				(font
					(size 1.27 1.27)
				)
			)
		)
		(property "Value" ""
			(at 0 0 0)
			(layer "F.Fab")
			(effects
				(font
					(size 1.27 1.27)
				)
			)
		)
		(duplicate_pad_numbers_are_jumpers no)
		(fp_line
			(start -0.7874 -0.4064)
			(end 0.7874 -0.4064)
			(stroke
				(width 0.1524)
				(type default)
			)
			(layer "F.SilkS")
		)
		(fp_line
			(start -0.7874 0.4064)
			(end -0.7874 -0.4064)
			(stroke
				(width 0.1524)
				(type default)
			)
			(layer "F.SilkS")
		)
		(fp_line
			(start 0.7874 -0.4064)
			(end 0.7874 0.4064)
			(stroke
				(width 0.1524)
				(type default)
			)
			(layer "F.SilkS")
		)
		(fp_line
			(start 0.7874 0.4064)
			(end -0.7874 0.4064)
			(stroke
				(width 0.1524)
				(type default)
			)
			(layer "F.SilkS")
		)
		(fp_line
			(start -0.67945 -0.305054)
			(end -0.12065 -0.305054)
			(stroke
				(width 0.1)
				(type default)
			)
			(layer "F.Fab")
		)
		(fp_line
			(start -0.67945 0.3048)
			(end -0.67945 -0.305054)
			(stroke
				(width 0.1)
				(type default)
			)
			(layer "F.Fab")
		)
		(fp_line
			(start -0.12065 -0.305054)
			(end -0.12065 -0.2794)
			(stroke
				(width 0.1)
				(type default)
			)
			(layer "F.Fab")
		)
		(fp_line
			(start -0.12065 -0.2794)
			(end 0.12065 -0.2794)
			(stroke
				(width 0.1)
				(type default)
			)
			(layer "F.Fab")
		)
		(fp_line
			(start -0.12065 0.2794)
			(end -0.12065 0.3048)
			(stroke
				(width 0.1)
				(type default)
			)
			(layer "F.Fab")
		)
		(fp_line
			(start -0.12065 0.3048)
			(end -0.67945 0.3048)
			(stroke
				(width 0.1)
				(type default)
			)
			(layer "F.Fab")
		)
		(fp_line
			(start 0.120396 0.2794)
			(end -0.12065 0.2794)
			(stroke
				(width 0.1)
				(type default)
			)
			(layer "F.Fab")
		)
		(fp_line
			(start 0.120396 0.3048)
			(end 0.120396 0.2794)
			(stroke
				(width 0.1)
				(type default)
			)
			(layer "F.Fab")
		)
		(fp_line
			(start 0.12065 -0.3048)
			(end 0.67945 -0.3048)
			(stroke
				(width 0.1)
				(type default)
			)
			(layer "F.Fab")
		)
		(fp_line
			(start 0.12065 -0.2794)
			(end 0.12065 -0.3048)
			(stroke
				(width 0.1)
				(type default)
			)
			(layer "F.Fab")
		)
		(fp_line
			(start 0.67945 -0.3048)
			(end 0.67945 0.3048)
			(stroke
				(width 0.1)
				(type default)
			)
			(layer "F.Fab")
		)
		(fp_line
			(start 0.67945 0.3048)
			(end 0.120396 0.3048)
			(stroke
				(width 0.1)
				(type default)
			)
			(layer "F.Fab")
		)
		(pad "1" smd circle
			(at -0.40005 0)
			(size 0 0)
			(layers "F.Cu" "F.Mask" "F.Paste")
			(net "P12V_SSD6")
		)
		(pad "2" smd circle
			(at 0.40005 0)
			(size 0 0)
			(layers "F.Cu" "F.Mask" "F.Paste")
			(net "GND")
		)
	)
	(footprint ""
		(layer "F.Cu")
		(at 119.255286 -53.468524 90)
		(property "Reference" "PC533"
			(at 0 0 90)
			(layer "F.SilkS")
			(hide yes)
			(effects
				(font
					(size 1.27 1.27)
				)
			)
		)
		(property "Value" ""
			(at 0 0 90)
			(layer "F.Fab")
			(effects
				(font
					(size 1.27 1.27)
				)
			)
		)
		(duplicate_pad_numbers_are_jumpers no)
		(fp_line
			(start 1.524 -0.762)
			(end 1.524 0.762)
			(stroke
				(width 0.1524)
				(type default)
			)
			(layer "F.SilkS")
		)
		(fp_line
			(start -1.524 -0.762)
			(end 1.524 -0.762)
			(stroke
				(width 0.1524)
				(type default)
			)
			(layer "F.SilkS")
		)
		(fp_line
			(start 1.524 0.762)
			(end -1.524 0.762)
			(stroke
				(width 0.1524)
				(type default)
			)
			(layer "F.SilkS")
		)
		(fp_line
			(start -1.524 0.762)
			(end -1.524 -0.762)
			(stroke
				(width 0.1524)
				(type default)
			)
			(layer "F.SilkS")
		)
		(fp_line
			(start 1.1049 -0.724916)
			(end -1.1049 -0.724916)
			(stroke
				(width 0.1)
				(type default)
			)
			(layer "F.Fab")
		)
		(fp_line
			(start -1.1049 -0.724916)
			(end -1.1049 0.724916)
			(stroke
				(width 0.1)
				(type default)
			)
			(layer "F.Fab")
		)
		(fp_line
			(start 1.1049 0.724916)
			(end 1.1049 -0.724916)
			(stroke
				(width 0.1)
				(type default)
			)
			(layer "F.Fab")
		)
		(fp_line
			(start -1.1049 0.724916)
			(end 1.1049 0.724916)
			(stroke
				(width 0.1)
				(type default)
			)
			(layer "F.Fab")
		)
		(pad "1" smd rect
			(at -0.889 0 270)
			(size 1.016 1.27)
			(layers "F.Cu" "F.Mask" "F.Paste")
			(net "GND")
		)
		(pad "2" smd rect
			(at 0.889 0 270)
			(size 1.016 1.27)
			(layers "F.Cu" "F.Mask" "F.Paste")
			(net "P3V3_AUX")
		)
	)
	(footprint ""
		(layer "F.Cu")
		(at 280.085546 -25.1587 -90)
		(property "Reference" "R5762"
			(at 0 0 270)
			(layer "F.SilkS")
			(hide yes)
			(effects
				(font
					(size 1.27 1.27)
				)
			)
		)
		(property "Value" ""
			(at 0 0 270)
			(layer "F.Fab")
			(effects
				(font
					(size 1.27 1.27)
				)
			)
		)
		(duplicate_pad_numbers_are_jumpers no)
		(fp_line
			(start -0.7874 0.4064)
			(end -0.7874 -0.4064)
			(stroke
				(width 0.1524)
				(type default)
			)
			(layer "F.SilkS")
		)
		(fp_line
			(start 0.7874 0.4064)
			(end -0.7874 0.4064)
			(stroke
				(width 0.1524)
				(type default)
			)
			(layer "F.SilkS")
		)
		(fp_line
			(start -0.7874 -0.4064)
			(end 0.7874 -0.4064)
			(stroke
				(width 0.1524)
				(type default)
			)
			(layer "F.SilkS")
		)
		(fp_line
			(start 0.7874 -0.4064)
			(end 0.7874 0.4064)
			(stroke
				(width 0.1524)
				(type default)
			)
			(layer "F.SilkS")
		)
		(fp_line
			(start -0.67945 0.3048)
			(end -0.67945 -0.305054)
			(stroke
				(width 0.1)
				(type default)
			)
			(layer "F.Fab")
		)
		(fp_line
			(start -0.12065 0.3048)
			(end -0.67945 0.3048)
			(stroke
				(width 0.1)
				(type default)
			)
			(layer "F.Fab")
		)
		(fp_line
			(start 0.120396 0.3048)
			(end 0.120396 0.2794)
			(stroke
				(width 0.1)
				(type default)
			)
			(layer "F.Fab")
		)
		(fp_line
			(start 0.67945 0.3048)
			(end 0.120396 0.3048)
			(stroke
				(width 0.1)
				(type default)
			)
			(layer "F.Fab")
		)
		(fp_line
			(start -0.12065 0.2794)
			(end -0.12065 0.3048)
			(stroke
				(width 0.1)
				(type default)
			)
			(layer "F.Fab")
		)
		(fp_line
			(start 0.120396 0.2794)
			(end -0.12065 0.2794)
			(stroke
				(width 0.1)
				(type default)
			)
			(layer "F.Fab")
		)
		(fp_line
			(start -0.12065 -0.2794)
			(end 0.12065 -0.2794)
			(stroke
				(width 0.1)
				(type default)
			)
			(layer "F.Fab")
		)
		(fp_line
			(start 0.12065 -0.2794)
			(end 0.12065 -0.3048)
			(stroke
				(width 0.1)
				(type default)
			)
			(layer "F.Fab")
		)
		(fp_line
			(start 0.12065 -0.3048)
			(end 0.67945 -0.3048)
			(stroke
				(width 0.1)
				(type default)
			)
			(layer "F.Fab")
		)
		(fp_line
			(start 0.67945 -0.3048)
			(end 0.67945 0.3048)
			(stroke
				(width 0.1)
				(type default)
			)
			(layer "F.Fab")
		)
		(fp_line
			(start -0.67945 -0.305054)
			(end -0.12065 -0.305054)
			(stroke
				(width 0.1)
				(type default)
			)
			(layer "F.Fab")
		)
		(fp_line
			(start -0.12065 -0.305054)
			(end -0.12065 -0.2794)
			(stroke
				(width 0.1)
				(type default)
			)
			(layer "F.Fab")
		)
		(pad "1" smd circle
			(at -0.40005 0 270)
			(size 0 0)
			(layers "F.Cu" "F.Mask" "F.Paste")
			(net "SSD9_LED_ISO_N")
		)
		(pad "2" smd circle
			(at 0.40005 0 270)
			(size 0 0)
			(layers "F.Cu" "F.Mask" "F.Paste")
			(net "SSD9_LED_ISO_R_N")
		)
	)
	(footprint ""
		(layer "F.Cu")
		(at 318.37884 -59.577986 -90)
		(property "Reference" "R901"
			(at 0 0 270)
			(layer "F.SilkS")
			(hide yes)
			(effects
				(font
					(size 1.27 1.27)
				)
			)
		)
		(property "Value" ""
			(at 0 0 270)
			(layer "F.Fab")
			(effects
				(font
					(size 1.27 1.27)
				)
			)
		)
		(duplicate_pad_numbers_are_jumpers no)
		(fp_line
			(start -0.7874 0.4064)
			(end -0.7874 -0.4064)
			(stroke
				(width 0.1524)
				(type default)
			)
			(layer "F.SilkS")
		)
		(fp_line
			(start 0.7874 0.4064)
			(end -0.7874 0.4064)
			(stroke
				(width 0.1524)
				(type default)
			)
			(layer "F.SilkS")
		)
		(fp_line
			(start -0.7874 -0.4064)
			(end 0.7874 -0.4064)
			(stroke
				(width 0.1524)
				(type default)
			)
			(layer "F.SilkS")
		)
		(fp_line
			(start 0.7874 -0.4064)
			(end 0.7874 0.4064)
			(stroke
				(width 0.1524)
				(type default)
			)
			(layer "F.SilkS")
		)
		(fp_line
			(start -0.67945 0.3048)
			(end -0.67945 -0.305054)
			(stroke
				(width 0.1)
				(type default)
			)
			(layer "F.Fab")
		)
		(fp_line
			(start -0.12065 0.3048)
			(end -0.67945 0.3048)
			(stroke
				(width 0.1)
				(type default)
			)
			(layer "F.Fab")
		)
		(fp_line
			(start 0.120396 0.3048)
			(end 0.120396 0.2794)
			(stroke
				(width 0.1)
				(type default)
			)
			(layer "F.Fab")
		)
		(fp_line
			(start 0.67945 0.3048)
			(end 0.120396 0.3048)
			(stroke
				(width 0.1)
				(type default)
			)
			(layer "F.Fab")
		)
		(fp_line
			(start -0.12065 0.2794)
			(end -0.12065 0.3048)
			(stroke
				(width 0.1)
				(type default)
			)
			(layer "F.Fab")
		)
		(fp_line
			(start 0.120396 0.2794)
			(end -0.12065 0.2794)
			(stroke
				(width 0.1)
				(type default)
			)
			(layer "F.Fab")
		)
		(fp_line
			(start -0.12065 -0.2794)
			(end 0.12065 -0.2794)
			(stroke
				(width 0.1)
				(type default)
			)
			(layer "F.Fab")
		)
		(fp_line
			(start 0.12065 -0.2794)
			(end 0.12065 -0.3048)
			(stroke
				(width 0.1)
				(type default)
			)
			(layer "F.Fab")
		)
		(fp_line
			(start 0.12065 -0.3048)
			(end 0.67945 -0.3048)
			(stroke
				(width 0.1)
				(type default)
			)
			(layer "F.Fab")
		)
		(fp_line
			(start 0.67945 -0.3048)
			(end 0.67945 0.3048)
			(stroke
				(width 0.1)
				(type default)
			)
			(layer "F.Fab")
		)
		(fp_line
			(start -0.67945 -0.305054)
			(end -0.12065 -0.305054)
			(stroke
				(width 0.1)
				(type default)
			)
			(layer "F.Fab")
		)
		(fp_line
			(start -0.12065 -0.305054)
			(end -0.12065 -0.2794)
			(stroke
				(width 0.1)
				(type default)
			)
			(layer "F.Fab")
		)
		(pad "1" smd circle
			(at -0.40005 0 270)
			(size 0 0)
			(layers "F.Cu" "F.Mask" "F.Paste")
			(net "P3V3_SSD11")
		)
		(pad "2" smd circle
			(at 0.40005 0 270)
			(size 0 0)
			(layers "F.Cu" "F.Mask" "F.Paste")
			(net "PWRGD_P3V3_SSD11")
		)
	)
)
